(kicad_pcb
	(version 20260206)
	(generator "pcbnew")
	(generator_version "10.0")
	(general
		(thickness 1.6)
		(legacy_teardrops no)
	)
	(paper "A4")
	(title_block
		(title "peb — Lightning_PEB_BRD.brd")
		(comment 1 "Lightning (Wiwynn / Facebook NVMe JBOF) / footprints 1109-1116 of 2563")
	)
	(layers
		(0 "F.Cu" signal "TOP")
		(4 "In1.Cu" signal "L2GND")
		(6 "In2.Cu" signal "L3")
		(8 "In3.Cu" signal "L4VCC")
		(10 "In4.Cu" signal "L5VCC")
		(12 "In5.Cu" signal "L6")
		(14 "In6.Cu" signal "L7GND")
		(2 "B.Cu" signal "BOTTOM")
		(9 "F.Adhes" user "F.Adhesive")
		(11 "B.Adhes" user "B.Adhesive")
		(13 "F.Paste" user "Package Geometry/Pastemask Top")
		(15 "B.Paste" user "Package Geometry/Pastemask Bottom")
		(5 "F.SilkS" user "Ref Des/Silkscreen Top")
		(7 "B.SilkS" user "Ref Des/Silkscreen Bottom")
		(1 "F.Mask" user "Board Geometry/Soldermask Top")
		(3 "B.Mask" user "Board Geometry/Soldermask Bottom")
		(17 "Dwgs.User" user "User.Drawings")
		(19 "Cmts.User" user "User.Comments")
		(21 "Eco1.User" user "User.Eco1")
		(23 "Eco2.User" user "User.Eco2")
		(25 "Edge.Cuts" user "Board Geometry/Outline")
		(27 "Margin" user)
		(31 "F.CrtYd" user "Package Geometry/Place Bound Top")
		(29 "B.CrtYd" user "Package Geometry/Place Bound Bottom")
		(35 "F.Fab" user "Ref Des/Assembly Top")
		(33 "B.Fab" user "Ref Des/Assembly Bottom")
	)
	(footprint ""
		(layer "F.Cu")
		(at 133.140958 -74.40676 180)
		(property "Reference" "R650"
			(at 0 0 180)
			(layer "F.SilkS")
			(hide yes)
			(effects
				(font
					(size 1.27 1.27)
				)
			)
		)
		(property "Value" "100KR2F-L1-GP"
			(at 0.064008 -3.993896 180)
			(unlocked yes)
			(layer "F.Fab")
			(hide yes)
			(effects
				(font
					(size 1.016 1.016)
					(thickness 0.1524)
				)
			)
		)
		(property "Device Type" "R402H16"
			(at 0.064008 -5.517896 180)
			(unlocked yes)
			(layer "F.Fab")
			(hide yes)
			(effects
				(font
					(size 1.016 1.016)
					(thickness 0.1524)
				)
			)
		)
		(duplicate_pad_numbers_are_jumpers no)
		(fp_line
			(start 0.508 -0.9398)
			(end -0.508 -0.9398)
			(stroke
				(width 0.1524)
				(type default)
			)
			(layer "F.SilkS")
		)
		(fp_line
			(start -0.508 -0.9398)
			(end -0.508 0.9398)
			(stroke
				(width 0.1524)
				(type default)
			)
			(layer "F.SilkS")
		)
		(fp_rect
			(start -0.508 0.9398)
			(end 0.508 -0.9398)
			(stroke
				(width 0)
				(type default)
			)
			(fill no)
			(layer "F.CrtYd")
		)
		(fp_rect
			(start -0.508 0.9398)
			(end 0.508 -0.9398)
			(stroke
				(width 0)
				(type default)
			)
			(fill no)
			(layer "F.Fab")
		)
		(pad "1" smd custom
			(at 0 -0.4445 180)
			(size 0.1397 0.1397)
			(layers "F.Cu" "F.Mask" "F.Paste")
			(net "DUT_VDDO")
			(options
				(clearance outline)
				(anchor circle)
			)
			(primitives
				(gr_poly
					(pts
						(arc
							(start -0.1778 -0.2794)
							(mid -0.249642 -0.249642)
							(end -0.2794 -0.1778)
						)
						(arc
							(start -0.2794 0.1778)
							(mid -0.249642 0.249642)
							(end -0.1778 0.2794)
						)
						(arc
							(start 0.1778 0.2794)
							(mid 0.249642 0.249642)
							(end 0.2794 0.1778)
						)
						(arc
							(start 0.2794 -0.1778)
							(mid 0.249642 -0.249642)
							(end 0.1778 -0.2794)
						)
					)
					(width 0)
					(fill yes)
				)
			)
		)
		(pad "2" smd custom
			(at 0 0.4445 180)
			(size 0.1397 0.1397)
			(layers "F.Cu" "F.Mask" "F.Paste")
			(net "SPI_DATA0_3_R")
			(options
				(clearance outline)
				(anchor circle)
			)
			(primitives
				(gr_poly
					(pts
						(arc
							(start -0.1778 -0.2794)
							(mid -0.249642 -0.249642)
							(end -0.2794 -0.1778)
						)
						(arc
							(start -0.2794 0.1778)
							(mid -0.249642 0.249642)
							(end -0.1778 0.2794)
						)
						(arc
							(start 0.1778 0.2794)
							(mid 0.249642 0.249642)
							(end 0.2794 0.1778)
						)
						(arc
							(start 0.2794 -0.1778)
							(mid 0.249642 -0.249642)
							(end 0.1778 -0.2794)
						)
					)
					(width 0)
					(fill yes)
				)
			)
		)
	)
	(footprint ""
		(layer "F.Cu")
		(at 34.181034 -103.656384 180)
		(property "Reference" "R53"
			(at 0 0 180)
			(layer "F.SilkS")
			(hide yes)
			(effects
				(font
					(size 1.27 1.27)
				)
			)
		)
		(property "Value" "0R2J-2-GP"
			(at 0.064008 -3.993896 180)
			(unlocked yes)
			(layer "F.Fab")
			(hide yes)
			(effects
				(font
					(size 1.016 1.016)
					(thickness 0.1524)
				)
			)
		)
		(property "Device Type" "R402H16"
			(at 0.064008 -5.517896 180)
			(unlocked yes)
			(layer "F.Fab")
			(hide yes)
			(effects
				(font
					(size 1.016 1.016)
					(thickness 0.1524)
				)
			)
		)
		(duplicate_pad_numbers_are_jumpers no)
		(fp_line
			(start 0.508 -0.9398)
			(end -0.508 -0.9398)
			(stroke
				(width 0.1524)
				(type default)
			)
			(layer "F.SilkS")
		)
		(fp_line
			(start -0.508 -0.9398)
			(end -0.508 0.9398)
			(stroke
				(width 0.1524)
				(type default)
			)
			(layer "F.SilkS")
		)
		(fp_rect
			(start -0.508 0.9398)
			(end 0.508 -0.9398)
			(stroke
				(width 0)
				(type default)
			)
			(fill no)
			(layer "F.CrtYd")
		)
		(fp_rect
			(start -0.508 0.9398)
			(end 0.508 -0.9398)
			(stroke
				(width 0)
				(type default)
			)
			(fill no)
			(layer "F.Fab")
		)
		(pad "1" smd custom
			(at 0 -0.4445 180)
			(size 0.1397 0.1397)
			(layers "F.Cu" "F.Mask" "F.Paste")
			(net "SPI_FLASH_SELECT_R")
			(options
				(clearance outline)
				(anchor circle)
			)
			(primitives
				(gr_poly
					(pts
						(arc
							(start -0.1778 -0.2794)
							(mid -0.249642 -0.249642)
							(end -0.2794 -0.1778)
						)
						(arc
							(start -0.2794 0.1778)
							(mid -0.249642 0.249642)
							(end -0.1778 0.2794)
						)
						(arc
							(start 0.1778 0.2794)
							(mid 0.249642 0.249642)
							(end 0.2794 0.1778)
						)
						(arc
							(start 0.2794 -0.1778)
							(mid 0.249642 -0.249642)
							(end 0.1778 -0.2794)
						)
					)
					(width 0)
					(fill yes)
				)
			)
		)
		(pad "2" smd custom
			(at 0 0.4445 180)
			(size 0.1397 0.1397)
			(layers "F.Cu" "F.Mask" "F.Paste")
			(net "SPI_FLASH_SELECT")
			(options
				(clearance outline)
				(anchor circle)
			)
			(primitives
				(gr_poly
					(pts
						(arc
							(start -0.1778 -0.2794)
							(mid -0.249642 -0.249642)
							(end -0.2794 -0.1778)
						)
						(arc
							(start -0.2794 0.1778)
							(mid -0.249642 0.249642)
							(end -0.1778 0.2794)
						)
						(arc
							(start 0.1778 0.2794)
							(mid 0.249642 0.249642)
							(end 0.2794 0.1778)
						)
						(arc
							(start 0.2794 -0.1778)
							(mid 0.249642 -0.249642)
							(end 0.1778 -0.2794)
						)
					)
					(width 0)
					(fill yes)
				)
			)
		)
	)
	(footprint ""
		(layer "F.Cu")
		(at 66.003678 -130.034792 180)
		(property "Reference" "C280"
			(at 0 0 180)
			(layer "F.SilkS")
			(hide yes)
			(effects
				(font
					(size 1.27 1.27)
				)
			)
		)
		(property "Value" "SCD1U16V2KX-3GP"
			(at 1.1811 -2.7051 180)
			(unlocked yes)
			(layer "F.Fab")
			(hide yes)
			(effects
				(font
					(size 1.016 1.016)
					(thickness 0.1524)
				)
			)
		)
		(property "Device Type" "C402H22"
			(at 1.1811 -4.2291 180)
			(unlocked yes)
			(layer "F.Fab")
			(hide yes)
			(effects
				(font
					(size 1.016 1.016)
					(thickness 0.1524)
				)
			)
		)
		(duplicate_pad_numbers_are_jumpers no)
		(fp_rect
			(start -0.4318 0.9525)
			(end 0.4318 -0.9525)
			(stroke
				(width 0)
				(type default)
			)
			(fill no)
			(layer "F.CrtYd")
		)
		(fp_rect
			(start -0.4318 0.9525)
			(end 0.4318 -0.9525)
			(stroke
				(width 0)
				(type default)
			)
			(fill no)
			(layer "F.Fab")
		)
		(pad "1" smd custom
			(at 0 -0.4445 180)
			(size 0.1524 0.1524)
			(layers "F.Cu" "F.Mask" "F.Paste")
			(net "P3V3_STBY")
			(options
				(clearance outline)
				(anchor circle)
			)
			(primitives
				(gr_poly
					(pts
						(arc
							(start 0.3048 -0.2032)
							(mid 0.275042 -0.275042)
							(end 0.2032 -0.3048)
						)
						(arc
							(start -0.2032 -0.3048)
							(mid -0.275042 -0.275042)
							(end -0.3048 -0.2032)
						)
						(arc
							(start -0.3048 0.2032)
							(mid -0.275042 0.275042)
							(end -0.2032 0.3048)
						)
						(arc
							(start 0.2032 0.3048)
							(mid 0.275042 0.275042)
							(end 0.3048 0.2032)
						)
					)
					(width 0)
					(fill yes)
				)
			)
		)
		(pad "2" smd custom
			(at 0 0.4445 180)
			(size 0.1524 0.1524)
			(layers "F.Cu" "F.Mask" "F.Paste")
			(net "GND")
			(options
				(clearance outline)
				(anchor circle)
			)
			(primitives
				(gr_poly
					(pts
						(arc
							(start 0.3048 -0.2032)
							(mid 0.275042 -0.275042)
							(end 0.2032 -0.3048)
						)
						(arc
							(start -0.2032 -0.3048)
							(mid -0.275042 -0.275042)
							(end -0.3048 -0.2032)
						)
						(arc
							(start -0.3048 0.2032)
							(mid -0.275042 0.275042)
							(end -0.2032 0.3048)
						)
						(arc
							(start 0.2032 0.3048)
							(mid 0.275042 0.275042)
							(end 0.3048 0.2032)
						)
					)
					(width 0)
					(fill yes)
				)
			)
		)
	)
	(footprint ""
		(layer "F.Cu")
		(at 52.959 -143.129)
		(property "Reference" "TP269"
			(at 0 0 0)
			(layer "F.SilkS")
			(hide yes)
			(effects
				(font
					(size 1.27 1.27)
				)
			)
		)
		(property "Value" "TPAD28-2-GP"
			(at -0.0127 -1.6637 0)
			(unlocked yes)
			(layer "F.Fab")
			(hide yes)
			(effects
				(font
					(size 1.016 1.016)
					(thickness 0.1524)
				)
			)
		)
		(property "Device Type" "TPAD28"
			(at -0.0127 -3.1877 0)
			(unlocked yes)
			(layer "F.Fab")
			(hide yes)
			(effects
				(font
					(size 1.016 1.016)
					(thickness 0.1524)
				)
			)
		)
		(duplicate_pad_numbers_are_jumpers no)
		(fp_poly
			(pts
				(arc
					(start 0.3556 0)
					(mid -0.3556 0)
					(end 0.3556 0)
				)
			)
			(stroke
				(width 0)
				(type default)
			)
			(fill no)
			(layer "F.CrtYd")
		)
		(fp_poly
			(pts
				(arc
					(start 0.6096 0)
					(mid -0.6096 0)
					(end 0.6096 0)
				)
			)
			(stroke
				(width 0)
				(type default)
			)
			(fill no)
			(layer "F.Fab")
		)
		(pad "1" smd circle
			(at 0 0)
			(size 0.7112 0.7112)
			(layers "F.Cu" "F.Mask" "F.Paste")
			(net "LED_DR_LED0")
		)
	)
	(footprint ""
		(layer "F.Cu")
		(at 255.314704 -10.988548)
		(property "Reference" "R31"
			(at 0 0 0)
			(layer "F.SilkS")
			(hide yes)
			(effects
				(font
					(size 1.27 1.27)
				)
			)
		)
		(property "Value" "4K7R2F-GP"
			(at 0.064008 -3.993896 0)
			(unlocked yes)
			(layer "F.Fab")
			(hide yes)
			(effects
				(font
					(size 1.016 1.016)
					(thickness 0.1524)
				)
			)
		)
		(property "Device Type" "R402H16"
			(at 0.064008 -5.517896 0)
			(unlocked yes)
			(layer "F.Fab")
			(hide yes)
			(effects
				(font
					(size 1.016 1.016)
					(thickness 0.1524)
				)
			)
		)
		(duplicate_pad_numbers_are_jumpers no)
		(fp_line
			(start -0.508 -0.9398)
			(end -0.508 0.9398)
			(stroke
				(width 0.1524)
				(type default)
			)
			(layer "F.SilkS")
		)
		(fp_line
			(start 0.508 -0.9398)
			(end -0.508 -0.9398)
			(stroke
				(width 0.1524)
				(type default)
			)
			(layer "F.SilkS")
		)
		(fp_rect
			(start -0.508 0.9398)
			(end 0.508 -0.9398)
			(stroke
				(width 0)
				(type default)
			)
			(fill no)
			(layer "F.CrtYd")
		)
		(fp_rect
			(start -0.508 0.9398)
			(end 0.508 -0.9398)
			(stroke
				(width 0)
				(type default)
			)
			(fill no)
			(layer "F.Fab")
		)
		(pad "1" smd custom
			(at 0 -0.4445)
			(size 0.1397 0.1397)
			(layers "F.Cu" "F.Mask" "F.Paste")
			(net "THERM_BASE")
			(options
				(clearance outline)
				(anchor circle)
			)
			(primitives
				(gr_poly
					(pts
						(arc
							(start -0.1778 -0.2794)
							(mid -0.249642 -0.249642)
							(end -0.2794 -0.1778)
						)
						(arc
							(start -0.2794 0.1778)
							(mid -0.249642 0.249642)
							(end -0.1778 0.2794)
						)
						(arc
							(start 0.1778 0.2794)
							(mid 0.249642 0.249642)
							(end 0.2794 0.1778)
						)
						(arc
							(start 0.2794 -0.1778)
							(mid 0.249642 -0.249642)
							(end 0.1778 -0.2794)
						)
					)
					(width 0)
					(fill yes)
				)
			)
		)
		(pad "2" smd custom
			(at 0 0.4445)
			(size 0.1397 0.1397)
			(layers "F.Cu" "F.Mask" "F.Paste")
			(net "GND")
			(options
				(clearance outline)
				(anchor circle)
			)
			(primitives
				(gr_poly
					(pts
						(arc
							(start -0.1778 -0.2794)
							(mid -0.249642 -0.249642)
							(end -0.2794 -0.1778)
						)
						(arc
							(start -0.2794 0.1778)
							(mid -0.249642 0.249642)
							(end -0.1778 0.2794)
						)
						(arc
							(start 0.1778 0.2794)
							(mid 0.249642 0.249642)
							(end 0.2794 0.1778)
						)
						(arc
							(start 0.2794 -0.1778)
							(mid 0.249642 -0.249642)
							(end 0.1778 -0.2794)
						)
					)
					(width 0)
					(fill yes)
				)
			)
		)
	)
	(footprint ""
		(layer "F.Cu")
		(at 53.721 -144.907 90)
		(property "Reference" "R257"
			(at 0 0 90)
			(layer "F.SilkS")
			(hide yes)
			(effects
				(font
					(size 1.27 1.27)
				)
			)
		)
		(property "Value" "4K7R2F-GP"
			(at 0.064008 -3.993896 90)
			(unlocked yes)
			(layer "F.Fab")
			(hide yes)
			(effects
				(font
					(size 1.016 1.016)
					(thickness 0.1524)
				)
			)
		)
		(property "Device Type" "R402H16"
			(at 0.064008 -5.517896 90)
			(unlocked yes)
			(layer "F.Fab")
			(hide yes)
			(effects
				(font
					(size 1.016 1.016)
					(thickness 0.1524)
				)
			)
		)
		(duplicate_pad_numbers_are_jumpers no)
		(fp_line
			(start 0.508 -0.9398)
			(end -0.508 -0.9398)
			(stroke
				(width 0.1524)
				(type default)
			)
			(layer "F.SilkS")
		)
		(fp_line
			(start -0.508 -0.9398)
			(end -0.508 0.9398)
			(stroke
				(width 0.1524)
				(type default)
			)
			(layer "F.SilkS")
		)
		(fp_rect
			(start -0.508 0.9398)
			(end 0.508 -0.9398)
			(stroke
				(width 0)
				(type default)
			)
			(fill no)
			(layer "F.CrtYd")
		)
		(fp_rect
			(start -0.508 0.9398)
			(end 0.508 -0.9398)
			(stroke
				(width 0)
				(type default)
			)
			(fill no)
			(layer "F.Fab")
		)
		(pad "1" smd custom
			(at 0 -0.4445 90)
			(size 0.1397 0.1397)
			(layers "F.Cu" "F.Mask" "F.Paste")
			(net "LED_DR_LED1")
			(options
				(clearance outline)
				(anchor circle)
			)
			(primitives
				(gr_poly
					(pts
						(arc
							(start -0.1778 -0.2794)
							(mid -0.249642 -0.249642)
							(end -0.2794 -0.1778)
						)
						(arc
							(start -0.2794 0.1778)
							(mid -0.249642 0.249642)
							(end -0.1778 0.2794)
						)
						(arc
							(start 0.1778 0.2794)
							(mid 0.249642 0.249642)
							(end 0.2794 0.1778)
						)
						(arc
							(start 0.2794 -0.1778)
							(mid 0.249642 -0.249642)
							(end 0.1778 -0.2794)
						)
					)
					(width 0)
					(fill yes)
				)
			)
		)
		(pad "2" smd custom
			(at 0 0.4445 90)
			(size 0.1397 0.1397)
			(layers "F.Cu" "F.Mask" "F.Paste")
			(net "P3V3_STBY")
			(options
				(clearance outline)
				(anchor circle)
			)
			(primitives
				(gr_poly
					(pts
						(arc
							(start -0.1778 -0.2794)
							(mid -0.249642 -0.249642)
							(end -0.2794 -0.1778)
						)
						(arc
							(start -0.2794 0.1778)
							(mid -0.249642 0.249642)
							(end -0.1778 0.2794)
						)
						(arc
							(start 0.1778 0.2794)
							(mid 0.249642 0.249642)
							(end 0.2794 0.1778)
						)
						(arc
							(start 0.2794 -0.1778)
							(mid 0.249642 -0.249642)
							(end 0.1778 -0.2794)
						)
					)
					(width 0)
					(fill yes)
				)
			)
		)
	)
	(footprint ""
		(layer "F.Cu")
		(at 55.808118 -212.420454 180)
		(property "Reference" "C362"
			(at 0 0 180)
			(layer "F.SilkS")
			(hide yes)
			(effects
				(font
					(size 1.27 1.27)
				)
			)
		)
		(property "Value" "SCD22U10V2KX-1GP"
			(at 1.1811 -2.7051 180)
			(unlocked yes)
			(layer "F.Fab")
			(hide yes)
			(effects
				(font
					(size 1.016 1.016)
					(thickness 0.1524)
				)
			)
		)
		(property "Device Type" "C402H22"
			(at 1.1811 -4.2291 180)
			(unlocked yes)
			(layer "F.Fab")
			(hide yes)
			(effects
				(font
					(size 1.016 1.016)
					(thickness 0.1524)
				)
			)
		)
		(duplicate_pad_numbers_are_jumpers no)
		(fp_rect
			(start -0.4318 0.9525)
			(end 0.4318 -0.9525)
			(stroke
				(width 0)
				(type default)
			)
			(fill no)
			(layer "F.CrtYd")
		)
		(fp_rect
			(start -0.4318 0.9525)
			(end 0.4318 -0.9525)
			(stroke
				(width 0)
				(type default)
			)
			(fill no)
			(layer "F.Fab")
		)
		(pad "1" smd custom
			(at 0 -0.4445 180)
			(size 0.1524 0.1524)
			(layers "F.Cu" "F.Mask" "F.Paste")
			(net "PCIE_TX_CAP_N73")
			(options
				(clearance outline)
				(anchor circle)
			)
			(primitives
				(gr_poly
					(pts
						(arc
							(start 0.3048 -0.2032)
							(mid 0.275042 -0.275042)
							(end 0.2032 -0.3048)
						)
						(arc
							(start -0.2032 -0.3048)
							(mid -0.275042 -0.275042)
							(end -0.3048 -0.2032)
						)
						(arc
							(start -0.3048 0.2032)
							(mid -0.275042 0.275042)
							(end -0.2032 0.3048)
						)
						(arc
							(start 0.2032 0.3048)
							(mid 0.275042 0.275042)
							(end 0.3048 0.2032)
						)
					)
					(width 0)
					(fill yes)
				)
			)
		)
		(pad "2" smd custom
			(at 0 0.4445 180)
			(size 0.1524 0.1524)
			(layers "F.Cu" "F.Mask" "F.Paste")
			(net "PCIE_TX_N73")
			(options
				(clearance outline)
				(anchor circle)
			)
			(primitives
				(gr_poly
					(pts
						(arc
							(start 0.3048 -0.2032)
							(mid 0.275042 -0.275042)
							(end 0.2032 -0.3048)
						)
						(arc
							(start -0.2032 -0.3048)
							(mid -0.275042 -0.275042)
							(end -0.3048 -0.2032)
						)
						(arc
							(start -0.3048 0.2032)
							(mid -0.275042 0.275042)
							(end -0.2032 0.3048)
						)
						(arc
							(start 0.2032 0.3048)
							(mid 0.275042 0.275042)
							(end 0.3048 0.2032)
						)
					)
					(width 0)
					(fill yes)
				)
			)
		)
	)
	(footprint ""
		(layer "F.Cu")
		(at 276.460458 -4.70535 90)
		(property "Reference" "R332"
			(at 0 0 90)
			(layer "F.SilkS")
			(hide yes)
			(effects
				(font
					(size 1.27 1.27)
				)
			)
		)
		(property "Value" "0R2J-2-GP"
			(at 0.064008 -3.993896 90)
			(unlocked yes)
			(layer "F.Fab")
			(hide yes)
			(effects
				(font
					(size 1.016 1.016)
					(thickness 0.1524)
				)
			)
		)
		(property "Device Type" "R402H16"
			(at 0.064008 -5.517896 90)
			(unlocked yes)
			(layer "F.Fab")
			(hide yes)
			(effects
				(font
					(size 1.016 1.016)
					(thickness 0.1524)
				)
			)
		)
		(duplicate_pad_numbers_are_jumpers no)
		(fp_line
			(start 0.508 -0.9398)
			(end -0.508 -0.9398)
			(stroke
				(width 0.1524)
				(type default)
			)
			(layer "F.SilkS")
		)
		(fp_line
			(start -0.508 -0.9398)
			(end -0.508 0.9398)
			(stroke
				(width 0.1524)
				(type default)
			)
			(layer "F.SilkS")
		)
		(fp_rect
			(start -0.508 0.9398)
			(end 0.508 -0.9398)
			(stroke
				(width 0)
				(type default)
			)
			(fill no)
			(layer "F.CrtYd")
		)
		(fp_rect
			(start -0.508 0.9398)
			(end 0.508 -0.9398)
			(stroke
				(width 0)
				(type default)
			)
			(fill no)
			(layer "F.Fab")
		)
		(pad "1" smd custom
			(at 0 -0.4445 90)
			(size 0.1397 0.1397)
			(layers "F.Cu" "F.Mask" "F.Paste")
			(net "CLK_P_6_R")
			(options
				(clearance outline)
				(anchor circle)
			)
			(primitives
				(gr_poly
					(pts
						(arc
							(start -0.1778 -0.2794)
							(mid -0.249642 -0.249642)
							(end -0.2794 -0.1778)
						)
						(arc
							(start -0.2794 0.1778)
							(mid -0.249642 0.249642)
							(end -0.1778 0.2794)
						)
						(arc
							(start 0.1778 0.2794)
							(mid 0.249642 0.249642)
							(end 0.2794 0.1778)
						)
						(arc
							(start 0.2794 -0.1778)
							(mid 0.249642 -0.249642)
							(end 0.1778 -0.2794)
						)
					)
					(width 0)
					(fill yes)
				)
			)
		)
		(pad "2" smd custom
			(at 0 0.4445 90)
			(size 0.1397 0.1397)
			(layers "F.Cu" "F.Mask" "F.Paste")
			(net "CLK_P_6")
			(options
				(clearance outline)
				(anchor circle)
			)
			(primitives
				(gr_poly
					(pts
						(arc
							(start -0.1778 -0.2794)
							(mid -0.249642 -0.249642)
							(end -0.2794 -0.1778)
						)
						(arc
							(start -0.2794 0.1778)
							(mid -0.249642 0.249642)
							(end -0.1778 0.2794)
						)
						(arc
							(start 0.1778 0.2794)
							(mid 0.249642 0.249642)
							(end 0.2794 0.1778)
						)
						(arc
							(start 0.2794 -0.1778)
							(mid 0.249642 -0.249642)
							(end 0.1778 -0.2794)
						)
					)
					(width 0)
					(fill yes)
				)
			)
		)
	)
)
